(kicad_pcb
	(version 20260206)
	(generator "pcbnew")
	(generator_version "10.0")
	(general
		(thickness 1.6)
		(legacy_teardrops no)
	)
	(paper "A4")
	(title_block
		(title "01162023_DA0F0TEBIF0_F0T_Expander_BD_F_brd_V02_OCP.brd")
		(comment 1 "Grand Teton / footprints 6844-6849 of 9728")
	)
	(layers
		(0 "F.Cu" signal "TOP")
		(4 "In1.Cu" signal "GND")
		(6 "In2.Cu" signal "VCC")
		(8 "In3.Cu" signal "VCC1")
		(10 "In4.Cu" signal "GND1")
		(12 "In5.Cu" signal "IN1")
		(14 "In6.Cu" signal "GND2")
		(16 "In7.Cu" signal "IN2")
		(18 "In8.Cu" signal "GND3")
		(20 "In9.Cu" signal "IN3")
		(22 "In10.Cu" signal "GND4")
		(24 "In11.Cu" signal "IN4")
		(26 "In12.Cu" signal "GND5")
		(28 "In13.Cu" signal "IN5")
		(30 "In14.Cu" signal "GND6")
		(32 "In15.Cu" signal "IN6")
		(34 "In16.Cu" signal "GND7")
		(2 "B.Cu" signal "BOTTOM")
		(9 "F.Adhes" user "F.Adhesive")
		(11 "B.Adhes" user "B.Adhesive")
		(13 "F.Paste" user "Package Geometry/Pastemask Top")
		(15 "B.Paste" user "Package Geometry/Pastemask Bottom")
		(5 "F.SilkS" user "Ref Des/Silkscreen Top")
		(7 "B.SilkS" user "Ref Des/Silkscreen Bottom")
		(1 "F.Mask" user "Board Geometry/Soldermask Top")
		(3 "B.Mask" user "Board Geometry/Soldermask Bottom")
		(17 "Dwgs.User" user "User.Drawings")
		(19 "Cmts.User" user "User.Comments")
		(21 "Eco1.User" user "User.Eco1")
		(23 "Eco2.User" user "User.Eco2")
		(25 "Edge.Cuts" user "Board Geometry/Outline")
		(27 "Margin" user)
		(31 "F.CrtYd" user "Package Geometry/Place Bound Top")
		(29 "B.CrtYd" user "Package Geometry/Place Bound Bottom")
		(35 "F.Fab" user "Ref Des/Assembly Top")
		(33 "B.Fab" user "Ref Des/Assembly Bottom")
	)
	(footprint ""
		(layer "F.Cu")
		(at 214.44839 -211.215732 180)
		(property "Reference" "R6413"
			(at 0 0 180)
			(layer "F.SilkS")
			(hide yes)
			(effects
				(font
					(size 1.27 1.27)
				)
			)
		)
		(property "Value" ""
			(at 0 0 180)
			(layer "F.Fab")
			(effects
				(font
					(size 1.27 1.27)
				)
			)
		)
		(duplicate_pad_numbers_are_jumpers no)
		(fp_line
			(start 0.7874 0.4064)
			(end -0.7874 0.4064)
			(stroke
				(width 0.1524)
				(type default)
			)
			(layer "F.SilkS")
		)
		(fp_line
			(start 0.7874 -0.4064)
			(end 0.7874 0.4064)
			(stroke
				(width 0.1524)
				(type default)
			)
			(layer "F.SilkS")
		)
		(fp_line
			(start -0.7874 0.4064)
			(end -0.7874 -0.4064)
			(stroke
				(width 0.1524)
				(type default)
			)
			(layer "F.SilkS")
		)
		(fp_line
			(start -0.7874 -0.4064)
			(end 0.7874 -0.4064)
			(stroke
				(width 0.1524)
				(type default)
			)
			(layer "F.SilkS")
		)
		(fp_line
			(start 0.67945 0.3048)
			(end 0.120396 0.3048)
			(stroke
				(width 0.1)
				(type default)
			)
			(layer "F.Fab")
		)
		(fp_line
			(start 0.67945 -0.3048)
			(end 0.67945 0.3048)
			(stroke
				(width 0.1)
				(type default)
			)
			(layer "F.Fab")
		)
		(fp_line
			(start 0.12065 -0.2794)
			(end 0.12065 -0.3048)
			(stroke
				(width 0.1)
				(type default)
			)
			(layer "F.Fab")
		)
		(fp_line
			(start 0.12065 -0.3048)
			(end 0.67945 -0.3048)
			(stroke
				(width 0.1)
				(type default)
			)
			(layer "F.Fab")
		)
		(fp_line
			(start 0.120396 0.3048)
			(end 0.120396 0.2794)
			(stroke
				(width 0.1)
				(type default)
			)
			(layer "F.Fab")
		)
		(fp_line
			(start 0.120396 0.2794)
			(end -0.12065 0.2794)
			(stroke
				(width 0.1)
				(type default)
			)
			(layer "F.Fab")
		)
		(fp_line
			(start -0.12065 0.3048)
			(end -0.67945 0.3048)
			(stroke
				(width 0.1)
				(type default)
			)
			(layer "F.Fab")
		)
		(fp_line
			(start -0.12065 0.2794)
			(end -0.12065 0.3048)
			(stroke
				(width 0.1)
				(type default)
			)
			(layer "F.Fab")
		)
		(fp_line
			(start -0.12065 -0.2794)
			(end 0.12065 -0.2794)
			(stroke
				(width 0.1)
				(type default)
			)
			(layer "F.Fab")
		)
		(fp_line
			(start -0.12065 -0.305054)
			(end -0.12065 -0.2794)
			(stroke
				(width 0.1)
				(type default)
			)
			(layer "F.Fab")
		)
		(fp_line
			(start -0.67945 0.3048)
			(end -0.67945 -0.305054)
			(stroke
				(width 0.1)
				(type default)
			)
			(layer "F.Fab")
		)
		(fp_line
			(start -0.67945 -0.305054)
			(end -0.12065 -0.305054)
			(stroke
				(width 0.1)
				(type default)
			)
			(layer "F.Fab")
		)
		(pad "1" smd circle
			(at -0.40005 0 180)
			(size 0 0)
			(layers "F.Cu" "F.Mask" "F.Paste")
			(net "RST_BIC_I2C9_SSD_MUX1_N")
		)
		(pad "2" smd circle
			(at 0.40005 0 180)
			(size 0 0)
			(layers "F.Cu" "F.Mask" "F.Paste")
			(net "P3V3_AUX")
		)
	)
	(footprint ""
		(layer "F.Cu")
		(at 123.71324 -138.360404 180)
		(property "Reference" "R4450"
			(at 0 0 180)
			(layer "F.SilkS")
			(hide yes)
			(effects
				(font
					(size 1.27 1.27)
				)
			)
		)
		(property "Value" ""
			(at 0 0 180)
			(layer "F.Fab")
			(effects
				(font
					(size 1.27 1.27)
				)
			)
		)
		(duplicate_pad_numbers_are_jumpers no)
		(fp_line
			(start 0.7874 0.4064)
			(end -0.7874 0.4064)
			(stroke
				(width 0.1524)
				(type default)
			)
			(layer "F.SilkS")
		)
		(fp_line
			(start 0.7874 -0.4064)
			(end 0.7874 0.4064)
			(stroke
				(width 0.1524)
				(type default)
			)
			(layer "F.SilkS")
		)
		(fp_line
			(start -0.7874 0.4064)
			(end -0.7874 -0.4064)
			(stroke
				(width 0.1524)
				(type default)
			)
			(layer "F.SilkS")
		)
		(fp_line
			(start -0.7874 -0.4064)
			(end 0.7874 -0.4064)
			(stroke
				(width 0.1524)
				(type default)
			)
			(layer "F.SilkS")
		)
		(fp_line
			(start 0.67945 0.3048)
			(end 0.120396 0.3048)
			(stroke
				(width 0.1)
				(type default)
			)
			(layer "F.Fab")
		)
		(fp_line
			(start 0.67945 -0.3048)
			(end 0.67945 0.3048)
			(stroke
				(width 0.1)
				(type default)
			)
			(layer "F.Fab")
		)
		(fp_line
			(start 0.12065 -0.2794)
			(end 0.12065 -0.3048)
			(stroke
				(width 0.1)
				(type default)
			)
			(layer "F.Fab")
		)
		(fp_line
			(start 0.12065 -0.3048)
			(end 0.67945 -0.3048)
			(stroke
				(width 0.1)
				(type default)
			)
			(layer "F.Fab")
		)
		(fp_line
			(start 0.120396 0.3048)
			(end 0.120396 0.2794)
			(stroke
				(width 0.1)
				(type default)
			)
			(layer "F.Fab")
		)
		(fp_line
			(start 0.120396 0.2794)
			(end -0.12065 0.2794)
			(stroke
				(width 0.1)
				(type default)
			)
			(layer "F.Fab")
		)
		(fp_line
			(start -0.12065 0.3048)
			(end -0.67945 0.3048)
			(stroke
				(width 0.1)
				(type default)
			)
			(layer "F.Fab")
		)
		(fp_line
			(start -0.12065 0.2794)
			(end -0.12065 0.3048)
			(stroke
				(width 0.1)
				(type default)
			)
			(layer "F.Fab")
		)
		(fp_line
			(start -0.12065 -0.2794)
			(end 0.12065 -0.2794)
			(stroke
				(width 0.1)
				(type default)
			)
			(layer "F.Fab")
		)
		(fp_line
			(start -0.12065 -0.305054)
			(end -0.12065 -0.2794)
			(stroke
				(width 0.1)
				(type default)
			)
			(layer "F.Fab")
		)
		(fp_line
			(start -0.67945 0.3048)
			(end -0.67945 -0.305054)
			(stroke
				(width 0.1)
				(type default)
			)
			(layer "F.Fab")
		)
		(fp_line
			(start -0.67945 -0.305054)
			(end -0.12065 -0.305054)
			(stroke
				(width 0.1)
				(type default)
			)
			(layer "F.Fab")
		)
		(pad "1" smd circle
			(at -0.40005 0 180)
			(size 0 0)
			(layers "F.Cu" "F.Mask" "F.Paste")
			(net "PWRGD_P12V_NIC2")
		)
		(pad "2" smd circle
			(at 0.40005 0 180)
			(size 0 0)
			(layers "F.Cu" "F.Mask" "F.Paste")
			(net "PWRGD_P12V_NIC2_R")
		)
	)
	(footprint ""
		(layer "F.Cu")
		(at 213.062566 -235.756958 90)
		(property "Reference" "R1540"
			(at 0 0 90)
			(layer "F.SilkS")
			(hide yes)
			(effects
				(font
					(size 1.27 1.27)
				)
			)
		)
		(property "Value" ""
			(at 0 0 90)
			(layer "F.Fab")
			(effects
				(font
					(size 1.27 1.27)
				)
			)
		)
		(duplicate_pad_numbers_are_jumpers no)
		(fp_line
			(start 0.7874 -0.4064)
			(end 0.7874 0.4064)
			(stroke
				(width 0.1524)
				(type default)
			)
			(layer "F.SilkS")
		)
		(fp_line
			(start -0.7874 -0.4064)
			(end 0.7874 -0.4064)
			(stroke
				(width 0.1524)
				(type default)
			)
			(layer "F.SilkS")
		)
		(fp_line
			(start 0.7874 0.4064)
			(end -0.7874 0.4064)
			(stroke
				(width 0.1524)
				(type default)
			)
			(layer "F.SilkS")
		)
		(fp_line
			(start -0.7874 0.4064)
			(end -0.7874 -0.4064)
			(stroke
				(width 0.1524)
				(type default)
			)
			(layer "F.SilkS")
		)
		(fp_line
			(start -0.12065 -0.305054)
			(end -0.12065 -0.2794)
			(stroke
				(width 0.1)
				(type default)
			)
			(layer "F.Fab")
		)
		(fp_line
			(start -0.67945 -0.305054)
			(end -0.12065 -0.305054)
			(stroke
				(width 0.1)
				(type default)
			)
			(layer "F.Fab")
		)
		(fp_line
			(start 0.67945 -0.3048)
			(end 0.67945 0.3048)
			(stroke
				(width 0.1)
				(type default)
			)
			(layer "F.Fab")
		)
		(fp_line
			(start 0.12065 -0.3048)
			(end 0.67945 -0.3048)
			(stroke
				(width 0.1)
				(type default)
			)
			(layer "F.Fab")
		)
		(fp_line
			(start 0.12065 -0.2794)
			(end 0.12065 -0.3048)
			(stroke
				(width 0.1)
				(type default)
			)
			(layer "F.Fab")
		)
		(fp_line
			(start -0.12065 -0.2794)
			(end 0.12065 -0.2794)
			(stroke
				(width 0.1)
				(type default)
			)
			(layer "F.Fab")
		)
		(fp_line
			(start 0.120396 0.2794)
			(end -0.12065 0.2794)
			(stroke
				(width 0.1)
				(type default)
			)
			(layer "F.Fab")
		)
		(fp_line
			(start -0.12065 0.2794)
			(end -0.12065 0.3048)
			(stroke
				(width 0.1)
				(type default)
			)
			(layer "F.Fab")
		)
		(fp_line
			(start 0.67945 0.3048)
			(end 0.120396 0.3048)
			(stroke
				(width 0.1)
				(type default)
			)
			(layer "F.Fab")
		)
		(fp_line
			(start 0.120396 0.3048)
			(end 0.120396 0.2794)
			(stroke
				(width 0.1)
				(type default)
			)
			(layer "F.Fab")
		)
		(fp_line
			(start -0.12065 0.3048)
			(end -0.67945 0.3048)
			(stroke
				(width 0.1)
				(type default)
			)
			(layer "F.Fab")
		)
		(fp_line
			(start -0.67945 0.3048)
			(end -0.67945 -0.305054)
			(stroke
				(width 0.1)
				(type default)
			)
			(layer "F.Fab")
		)
		(pad "1" smd circle
			(at -0.40005 0 90)
			(size 0 0)
			(layers "F.Cu" "F.Mask" "F.Paste")
			(net "P1V8_PEX")
		)
		(pad "2" smd circle
			(at 0.40005 0 90)
			(size 0 0)
			(layers "F.Cu" "F.Mask" "F.Paste")
			(net "SMB_PEX_LS_SDA")
		)
	)
	(footprint ""
		(layer "F.Cu")
		(at 377.455176 -53.468524 90)
		(property "Reference" "PC559"
			(at 0 0 90)
			(layer "F.SilkS")
			(hide yes)
			(effects
				(font
					(size 1.27 1.27)
				)
			)
		)
		(property "Value" ""
			(at 0 0 90)
			(layer "F.Fab")
			(effects
				(font
					(size 1.27 1.27)
				)
			)
		)
		(duplicate_pad_numbers_are_jumpers no)
		(fp_line
			(start 1.524 -0.762)
			(end 1.524 0.762)
			(stroke
				(width 0.1524)
				(type default)
			)
			(layer "F.SilkS")
		)
		(fp_line
			(start -1.524 -0.762)
			(end 1.524 -0.762)
			(stroke
				(width 0.1524)
				(type default)
			)
			(layer "F.SilkS")
		)
		(fp_line
			(start 1.524 0.762)
			(end -1.524 0.762)
			(stroke
				(width 0.1524)
				(type default)
			)
			(layer "F.SilkS")
		)
		(fp_line
			(start -1.524 0.762)
			(end -1.524 -0.762)
			(stroke
				(width 0.1524)
				(type default)
			)
			(layer "F.SilkS")
		)
		(fp_line
			(start 1.1049 -0.724916)
			(end -1.1049 -0.724916)
			(stroke
				(width 0.1)
				(type default)
			)
			(layer "F.Fab")
		)
		(fp_line
			(start -1.1049 -0.724916)
			(end -1.1049 0.724916)
			(stroke
				(width 0.1)
				(type default)
			)
			(layer "F.Fab")
		)
		(fp_line
			(start 1.1049 0.724916)
			(end 1.1049 -0.724916)
			(stroke
				(width 0.1)
				(type default)
			)
			(layer "F.Fab")
		)
		(fp_line
			(start -1.1049 0.724916)
			(end 1.1049 0.724916)
			(stroke
				(width 0.1)
				(type default)
			)
			(layer "F.Fab")
		)
		(pad "1" smd rect
			(at -0.889 0 270)
			(size 1.016 1.27)
			(layers "F.Cu" "F.Mask" "F.Paste")
			(net "GND")
		)
		(pad "2" smd rect
			(at 0.889 0 270)
			(size 1.016 1.27)
			(layers "F.Cu" "F.Mask" "F.Paste")
			(net "P3V3_AUX")
		)
	)
	(footprint ""
		(layer "F.Cu")
		(at 82.666078 -77.889608 180)
		(property "Reference" "C868"
			(at 0 0 180)
			(layer "F.SilkS")
			(hide yes)
			(effects
				(font
					(size 1.27 1.27)
				)
			)
		)
		(property "Value" ""
			(at 0 0 180)
			(layer "F.Fab")
			(effects
				(font
					(size 1.27 1.27)
				)
			)
		)
		(duplicate_pad_numbers_are_jumpers no)
		(fp_line
			(start 0.7874 0.4064)
			(end -0.7874 0.4064)
			(stroke
				(width 0.1524)
				(type default)
			)
			(layer "F.SilkS")
		)
		(fp_line
			(start 0.7874 -0.4064)
			(end 0.7874 0.4064)
			(stroke
				(width 0.1524)
				(type default)
			)
			(layer "F.SilkS")
		)
		(fp_line
			(start -0.7874 0.4064)
			(end -0.7874 -0.4064)
			(stroke
				(width 0.1524)
				(type default)
			)
			(layer "F.SilkS")
		)
		(fp_line
			(start -0.7874 -0.4064)
			(end 0.7874 -0.4064)
			(stroke
				(width 0.1524)
				(type default)
			)
			(layer "F.SilkS")
		)
		(fp_line
			(start 0.67945 0.3048)
			(end 0.120396 0.3048)
			(stroke
				(width 0.1)
				(type default)
			)
			(layer "F.Fab")
		)
		(fp_line
			(start 0.67945 -0.3048)
			(end 0.67945 0.3048)
			(stroke
				(width 0.1)
				(type default)
			)
			(layer "F.Fab")
		)
		(fp_line
			(start 0.12065 -0.2794)
			(end 0.12065 -0.3048)
			(stroke
				(width 0.1)
				(type default)
			)
			(layer "F.Fab")
		)
		(fp_line
			(start 0.12065 -0.3048)
			(end 0.67945 -0.3048)
			(stroke
				(width 0.1)
				(type default)
			)
			(layer "F.Fab")
		)
		(fp_line
			(start 0.120396 0.3048)
			(end 0.120396 0.2794)
			(stroke
				(width 0.1)
				(type default)
			)
			(layer "F.Fab")
		)
		(fp_line
			(start 0.120396 0.2794)
			(end -0.12065 0.2794)
			(stroke
				(width 0.1)
				(type default)
			)
			(layer "F.Fab")
		)
		(fp_line
			(start -0.12065 0.3048)
			(end -0.67945 0.3048)
			(stroke
				(width 0.1)
				(type default)
			)
			(layer "F.Fab")
		)
		(fp_line
			(start -0.12065 0.2794)
			(end -0.12065 0.3048)
			(stroke
				(width 0.1)
				(type default)
			)
			(layer "F.Fab")
		)
		(fp_line
			(start -0.12065 -0.2794)
			(end 0.12065 -0.2794)
			(stroke
				(width 0.1)
				(type default)
			)
			(layer "F.Fab")
		)
		(fp_line
			(start -0.12065 -0.305054)
			(end -0.12065 -0.2794)
			(stroke
				(width 0.1)
				(type default)
			)
			(layer "F.Fab")
		)
		(fp_line
			(start -0.67945 0.3048)
			(end -0.67945 -0.305054)
			(stroke
				(width 0.1)
				(type default)
			)
			(layer "F.Fab")
		)
		(fp_line
			(start -0.67945 -0.305054)
			(end -0.12065 -0.305054)
			(stroke
				(width 0.1)
				(type default)
			)
			(layer "F.Fab")
		)
		(pad "1" smd circle
			(at -0.40005 0 180)
			(size 0 0)
			(layers "F.Cu" "F.Mask" "F.Paste")
			(net "P3V3_NIC1")
		)
		(pad "2" smd circle
			(at 0.40005 0 180)
			(size 0 0)
			(layers "F.Cu" "F.Mask" "F.Paste")
			(net "GND")
		)
	)
	(footprint ""
		(layer "F.Cu")
		(at 327.53173 -223.972882)
		(property "Reference" "R4171"
			(at 0 0 0)
			(layer "F.SilkS")
			(hide yes)
			(effects
				(font
					(size 1.27 1.27)
				)
			)
		)
		(property "Value" ""
			(at 0 0 0)
			(layer "F.Fab")
			(effects
				(font
					(size 1.27 1.27)
				)
			)
		)
		(duplicate_pad_numbers_are_jumpers no)
		(fp_line
			(start -0.7874 -0.4064)
			(end 0.7874 -0.4064)
			(stroke
				(width 0.1524)
				(type default)
			)
			(layer "F.SilkS")
		)
		(fp_line
			(start -0.7874 0.4064)
			(end -0.7874 -0.4064)
			(stroke
				(width 0.1524)
				(type default)
			)
			(layer "F.SilkS")
		)
		(fp_line
			(start 0.7874 -0.4064)
			(end 0.7874 0.4064)
			(stroke
				(width 0.1524)
				(type default)
			)
			(layer "F.SilkS")
		)
		(fp_line
			(start 0.7874 0.4064)
			(end -0.7874 0.4064)
			(stroke
				(width 0.1524)
				(type default)
			)
			(layer "F.SilkS")
		)
		(fp_line
			(start -0.67945 -0.305054)
			(end -0.12065 -0.305054)
			(stroke
				(width 0.1)
				(type default)
			)
			(layer "F.Fab")
		)
		(fp_line
			(start -0.67945 0.3048)
			(end -0.67945 -0.305054)
			(stroke
				(width 0.1)
				(type default)
			)
			(layer "F.Fab")
		)
		(fp_line
			(start -0.12065 -0.305054)
			(end -0.12065 -0.2794)
			(stroke
				(width 0.1)
				(type default)
			)
			(layer "F.Fab")
		)
		(fp_line
			(start -0.12065 -0.2794)
			(end 0.12065 -0.2794)
			(stroke
				(width 0.1)
				(type default)
			)
			(layer "F.Fab")
		)
		(fp_line
			(start -0.12065 0.2794)
			(end -0.12065 0.3048)
			(stroke
				(width 0.1)
				(type default)
			)
			(layer "F.Fab")
		)
		(fp_line
			(start -0.12065 0.3048)
			(end -0.67945 0.3048)
			(stroke
				(width 0.1)
				(type default)
			)
			(layer "F.Fab")
		)
		(fp_line
			(start 0.120396 0.2794)
			(end -0.12065 0.2794)
			(stroke
				(width 0.1)
				(type default)
			)
			(layer "F.Fab")
		)
		(fp_line
			(start 0.120396 0.3048)
			(end 0.120396 0.2794)
			(stroke
				(width 0.1)
				(type default)
			)
			(layer "F.Fab")
		)
		(fp_line
			(start 0.12065 -0.3048)
			(end 0.67945 -0.3048)
			(stroke
				(width 0.1)
				(type default)
			)
			(layer "F.Fab")
		)
		(fp_line
			(start 0.12065 -0.2794)
			(end 0.12065 -0.3048)
			(stroke
				(width 0.1)
				(type default)
			)
			(layer "F.Fab")
		)
		(fp_line
			(start 0.67945 -0.3048)
			(end 0.67945 0.3048)
			(stroke
				(width 0.1)
				(type default)
			)
			(layer "F.Fab")
		)
		(fp_line
			(start 0.67945 0.3048)
			(end 0.120396 0.3048)
			(stroke
				(width 0.1)
				(type default)
			)
			(layer "F.Fab")
		)
		(pad "1" smd circle
			(at -0.40005 0)
			(size 0 0)
			(layers "F.Cu" "F.Mask" "F.Paste")
			(net "RST_PEX0_PERST_R_N")
		)
		(pad "2" smd circle
			(at 0.40005 0)
			(size 0 0)
			(layers "F.Cu" "F.Mask" "F.Paste")
			(net "RST_PEX0_PERST_N")
		)
	)
)
